# S9S_MB_2U (Grand Teton) — schematic netlist excerpt (pin names and nets, part order shuffled) for the footprints in the layout excerpt that follows; sources: Cadence DE-HDL packaged netlist, KiCad conversion of 03242023_DA0F0TMBIJ0_F0T_Motherboard_J_brd_V01_OCP.brd

C47  Q_CAP  2.2UF 6.3V 20% X6S  pkg C0402  page 97 : A = P3V3_AUX ; B = GND
PR2511  Q_RES  1 1% EMPTY  pkg 0402LF  page 304 : A = P12V_HSC_ADC_P ; B = P12V_HSC_SENSE2_R2_P

(kicad_pcb
	(version 20260206)
	(generator "pcbnew")
	(generator_version "10.0")
	(general
		(thickness 1.6)
		(legacy_teardrops no)
	)
	(paper "A4")
	(title_block
		(title "03242023_DA0F0TMBIJ0_F0T_Motherboard_J_brd_V01_OCP.brd")
		(comment 1 "Grand Teton / footprints 4372-4373 of 6105")
	)
	(layers
		(0 "F.Cu" signal "TOP")
		(4 "In1.Cu" signal "GND")
		(6 "In2.Cu" signal "IN1")
		(8 "In3.Cu" signal "GND1")
		(10 "In4.Cu" signal "IN2")
		(12 "In5.Cu" signal "GND2")
		(14 "In6.Cu" signal "IN3")
		(16 "In7.Cu" signal "GND3")
		(18 "In8.Cu" signal "VCC")
		(20 "In9.Cu" signal "VCC1")
		(22 "In10.Cu" signal "GND4")
		(24 "In11.Cu" signal "IN4")
		(26 "In12.Cu" signal "GND5")
		(28 "In13.Cu" signal "IN5")
		(30 "In14.Cu" signal "GND6")
		(32 "In15.Cu" signal "IN6")
		(34 "In16.Cu" signal "GND7")
		(2 "B.Cu" signal "BOTTOM")
		(9 "F.Adhes" user "F.Adhesive")
		(11 "B.Adhes" user "B.Adhesive")
		(13 "F.Paste" user "Package Geometry/Pastemask Top")
		(15 "B.Paste" user "Package Geometry/Pastemask Bottom")
		(5 "F.SilkS" user "Ref Des/Silkscreen Top")
		(7 "B.SilkS" user "Ref Des/Silkscreen Bottom")
		(1 "F.Mask" user "Board Geometry/Soldermask Top")
		(3 "B.Mask" user "Board Geometry/Soldermask Bottom")
		(17 "Dwgs.User" user "User.Drawings")
		(19 "Cmts.User" user "User.Comments")
		(21 "Eco1.User" user "User.Eco1")
		(23 "Eco2.User" user "User.Eco2")
		(25 "Edge.Cuts" user "Board Geometry/Outline")
		(27 "Margin" user)
		(31 "F.CrtYd" user "Package Geometry/Place Bound Top")
		(29 "B.CrtYd" user "Package Geometry/Place Bound Bottom")
		(35 "F.Fab" user "Ref Des/Assembly Top")
		(33 "B.Fab" user "Ref Des/Assembly Bottom")
	)
	(footprint ""
		(layer "B.Cu")
		(at 291.004498 -403.031452 90)
		(property "Reference" "PR2511"
			(at 0 0 90)
			(layer "B.SilkS")
			(hide yes)
			(effects
				(font
					(size 1.27 1.27)
				)
				(justify mirror)
			)
		)
		(property "Value" ""
			(at 0 0 90)
			(layer "B.Fab")
			(effects
				(font
					(size 1.27 1.27)
				)
				(justify mirror)
			)
		)
		(duplicate_pad_numbers_are_jumpers no)
		(fp_line
			(start 0.7874 -0.4064)
			(end -0.7874 -0.4064)
			(stroke
				(width 0.1524)
				(type default)
			)
			(layer "B.SilkS")
		)
		(fp_line
			(start -0.7874 -0.4064)
			(end -0.7874 0.4064)
			(stroke
				(width 0.1524)
				(type default)
			)
			(layer "B.SilkS")
		)
		(fp_line
			(start 0.7874 0.4064)
			(end 0.7874 -0.4064)
			(stroke
				(width 0.1524)
				(type default)
			)
			(layer "B.SilkS")
		)
		(fp_line
			(start -0.7874 0.4064)
			(end 0.7874 0.4064)
			(stroke
				(width 0.1524)
				(type default)
			)
			(layer "B.SilkS")
		)
		(fp_line
			(start 0.67945 -0.305054)
			(end 0.12065 -0.305054)
			(stroke
				(width 0.1)
				(type default)
			)
			(layer "B.Fab")
		)
		(fp_line
			(start 0.12065 -0.305054)
			(end 0.12065 -0.2794)
			(stroke
				(width 0.1)
				(type default)
			)
			(layer "B.Fab")
		)
		(fp_line
			(start -0.12065 -0.3048)
			(end -0.67945 -0.3048)
			(stroke
				(width 0.1)
				(type default)
			)
			(layer "B.Fab")
		)
		(fp_line
			(start -0.67945 -0.3048)
			(end -0.67945 0.3048)
			(stroke
				(width 0.1)
				(type default)
			)
			(layer "B.Fab")
		)
		(fp_line
			(start 0.12065 -0.2794)
			(end -0.12065 -0.2794)
			(stroke
				(width 0.1)
				(type default)
			)
			(layer "B.Fab")
		)
		(fp_line
			(start -0.12065 -0.2794)
			(end -0.12065 -0.3048)
			(stroke
				(width 0.1)
				(type default)
			)
			(layer "B.Fab")
		)
		(fp_line
			(start 0.12065 0.2794)
			(end 0.12065 0.3048)
			(stroke
				(width 0.1)
				(type default)
			)
			(layer "B.Fab")
		)
		(fp_line
			(start -0.120396 0.2794)
			(end 0.12065 0.2794)
			(stroke
				(width 0.1)
				(type default)
			)
			(layer "B.Fab")
		)
		(fp_line
			(start 0.67945 0.3048)
			(end 0.67945 -0.305054)
			(stroke
				(width 0.1)
				(type default)
			)
			(layer "B.Fab")
		)
		(fp_line
			(start 0.12065 0.3048)
			(end 0.67945 0.3048)
			(stroke
				(width 0.1)
				(type default)
			)
			(layer "B.Fab")
		)
		(fp_line
			(start -0.120396 0.3048)
			(end -0.120396 0.2794)
			(stroke
				(width 0.1)
				(type default)
			)
			(layer "B.Fab")
		)
		(fp_line
			(start -0.67945 0.3048)
			(end -0.120396 0.3048)
			(stroke
				(width 0.1)
				(type default)
			)
			(layer "B.Fab")
		)
		(pad "1" smd circle
			(at 0.40005 0 270)
			(size 0 0)
			(layers "B.Cu" "B.Mask" "B.Paste")
			(net "P12V_HSC_ADC_P")
		)
		(pad "2" smd circle
			(at -0.40005 0 270)
			(size 0 0)
			(layers "B.Cu" "B.Mask" "B.Paste")
			(net "P12V_HSC_SENSE2_R2_P")
		)
	)
	(footprint ""
		(layer "B.Cu")
		(at 452.028814 -319.263776 180)
		(property "Reference" "C47"
			(at 0 0 0)
			(layer "B.SilkS")
			(hide yes)
			(effects
				(font
					(size 1.27 1.27)
				)
				(justify mirror)
			)
		)
		(property "Value" ""
			(at 0 0 0)
			(layer "B.Fab")
			(effects
				(font
					(size 1.27 1.27)
				)
				(justify mirror)
			)
		)
		(duplicate_pad_numbers_are_jumpers no)
		(fp_line
			(start 0.7874 0.4064)
			(end 0.7874 -0.4064)
			(stroke
				(width 0.1524)
				(type default)
			)
			(layer "B.SilkS")
		)
		(fp_line
			(start 0.7874 -0.4064)
			(end -0.7874 -0.4064)
			(stroke
				(width 0.1524)
				(type default)
			)
			(layer "B.SilkS")
		)
		(fp_line
			(start -0.7874 0.4064)
			(end 0.7874 0.4064)
			(stroke
				(width 0.1524)
				(type default)
			)
			(layer "B.SilkS")
		)
		(fp_line
			(start -0.7874 -0.4064)
			(end -0.7874 0.4064)
			(stroke
				(width 0.1524)
				(type default)
			)
			(layer "B.SilkS")
		)
		(fp_line
			(start 0.67945 0.3048)
			(end 0.67945 -0.305054)
			(stroke
				(width 0.1)
				(type default)
			)
			(layer "B.Fab")
		)
		(fp_line
			(start 0.67945 -0.305054)
			(end 0.12065 -0.305054)
			(stroke
				(width 0.1)
				(type default)
			)
			(layer "B.Fab")
		)
		(fp_line
			(start 0.12065 0.3048)
			(end 0.67945 0.3048)
			(stroke
				(width 0.1)
				(type default)
			)
			(layer "B.Fab")
		)
		(fp_line
			(start 0.12065 0.2794)
			(end 0.12065 0.3048)
			(stroke
				(width 0.1)
				(type default)
			)
			(layer "B.Fab")
		)
		(fp_line
			(start 0.12065 -0.2794)
			(end -0.12065 -0.2794)
			(stroke
				(width 0.1)
				(type default)
			)
			(layer "B.Fab")
		)
		(fp_line
			(start 0.12065 -0.305054)
			(end 0.12065 -0.2794)
			(stroke
				(width 0.1)
				(type default)
			)
			(layer "B.Fab")
		)
		(fp_line
			(start -0.120396 0.3048)
			(end -0.120396 0.2794)
			(stroke
				(width 0.1)
				(type default)
			)
			(layer "B.Fab")
		)
		(fp_line
			(start -0.120396 0.2794)
			(end 0.12065 0.2794)
			(stroke
				(width 0.1)
				(type default)
			)
			(layer "B.Fab")
		)
		(fp_line
			(start -0.12065 -0.2794)
			(end -0.12065 -0.3048)
			(stroke
				(width 0.1)
				(type default)
			)
			(layer "B.Fab")
		)
		(fp_line
			(start -0.12065 -0.3048)
			(end -0.67945 -0.3048)
			(stroke
				(width 0.1)
				(type default)
			)
			(layer "B.Fab")
		)
		(fp_line
			(start -0.67945 0.3048)
			(end -0.120396 0.3048)
			(stroke
				(width 0.1)
				(type default)
			)
			(layer "B.Fab")
		)
		(fp_line
			(start -0.67945 -0.3048)
			(end -0.67945 0.3048)
			(stroke
				(width 0.1)
				(type default)
			)
			(layer "B.Fab")
		)
		(pad "1" smd circle
			(at 0.40005 0)
			(size 0 0)
			(layers "B.Cu" "B.Mask" "B.Paste")
			(net "P3V3_AUX")
		)
		(pad "2" smd circle
			(at -0.40005 0)
			(size 0 0)
			(layers "B.Cu" "B.Mask" "B.Paste")
			(net "GND")
		)
	)
)
